# T6G (Grand Teton) — schematic netlist excerpt (pin names and nets, part order shuffled) for the footprints in the layout excerpt that follows; sources: Cadence DE-HDL packaged netlist, KiCad conversion of 04192023_DAF0TMB3IC0_F0TG_MB_C_brd_V02_OCP.brd

R526  Q_RES  1K 1% CHIP  pkg 0402LF  page 54 : A = PVDD18_S5_P1 ; B = JTAG_CPU1_TCK
PR439  Q_RES  1K 1% CHIP  pkg 0402LF  page 209 : A = PVDD18_S5_P0 ; B = GND

(kicad_pcb
	(version 20260206)
	(generator "pcbnew")
	(generator_version "10.0")
	(general
		(thickness 1.6)
		(legacy_teardrops no)
	)
	(paper "A4")
	(title_block
		(title "04192023_DAF0TMB3IC0_F0TG_MB_C_brd_V02_OCP.brd")
		(comment 1 "Grand Teton / footprints 7608-7609 of 8354")
	)
	(layers
		(0 "F.Cu" signal "TOP")
		(4 "In1.Cu" signal "GND")
		(6 "In2.Cu" signal "IN1")
		(8 "In3.Cu" signal "GND1")
		(10 "In4.Cu" signal "IN2")
		(12 "In5.Cu" signal "GND2")
		(14 "In6.Cu" signal "IN3")
		(16 "In7.Cu" signal "GND3")
		(18 "In8.Cu" signal "VCC")
		(20 "In9.Cu" signal "VCC1")
		(22 "In10.Cu" signal "GND4")
		(24 "In11.Cu" signal "IN4")
		(26 "In12.Cu" signal "GND5")
		(28 "In13.Cu" signal "IN5")
		(30 "In14.Cu" signal "GND6")
		(32 "In15.Cu" signal "IN6")
		(34 "In16.Cu" signal "GND7")
		(2 "B.Cu" signal "BOTTOM")
		(9 "F.Adhes" user "F.Adhesive")
		(11 "B.Adhes" user "B.Adhesive")
		(13 "F.Paste" user "Package Geometry/Pastemask Top")
		(15 "B.Paste" user "Package Geometry/Pastemask Bottom")
		(5 "F.SilkS" user "Ref Des/Silkscreen Top")
		(7 "B.SilkS" user "Ref Des/Silkscreen Bottom")
		(1 "F.Mask" user "Board Geometry/Soldermask Top")
		(3 "B.Mask" user "Board Geometry/Soldermask Bottom")
		(17 "Dwgs.User" user "User.Drawings")
		(19 "Cmts.User" user "User.Comments")
		(21 "Eco1.User" user "User.Eco1")
		(23 "Eco2.User" user "User.Eco2")
		(25 "Edge.Cuts" user "Board Geometry/Outline")
		(27 "Margin" user)
		(31 "F.CrtYd" user "Package Geometry/Place Bound Top")
		(29 "B.CrtYd" user "Package Geometry/Place Bound Bottom")
		(35 "F.Fab" user "Ref Des/Assembly Top")
		(33 "B.Fab" user "Ref Des/Assembly Bottom")
	)
	(footprint ""
		(layer "B.Cu")
		(at 332.187296 -151.132794 90)
		(property "Reference" "PR439"
			(at 0 0 90)
			(layer "B.SilkS")
			(hide yes)
			(effects
				(font
					(size 1.27 1.27)
				)
				(justify mirror)
			)
		)
		(property "Value" ""
			(at 0 0 90)
			(layer "B.Fab")
			(effects
				(font
					(size 1.27 1.27)
				)
				(justify mirror)
			)
		)
		(duplicate_pad_numbers_are_jumpers no)
		(fp_line
			(start 0.7874 -0.4064)
			(end -0.7874 -0.4064)
			(stroke
				(width 0.1524)
				(type default)
			)
			(layer "B.SilkS")
		)
		(fp_line
			(start -0.7874 -0.4064)
			(end -0.7874 0.4064)
			(stroke
				(width 0.1524)
				(type default)
			)
			(layer "B.SilkS")
		)
		(fp_line
			(start 0.7874 0.4064)
			(end 0.7874 -0.4064)
			(stroke
				(width 0.1524)
				(type default)
			)
			(layer "B.SilkS")
		)
		(fp_line
			(start -0.7874 0.4064)
			(end 0.7874 0.4064)
			(stroke
				(width 0.1524)
				(type default)
			)
			(layer "B.SilkS")
		)
		(fp_line
			(start 0.67945 -0.305054)
			(end 0.12065 -0.305054)
			(stroke
				(width 0.1)
				(type default)
			)
			(layer "B.Fab")
		)
		(fp_line
			(start 0.12065 -0.305054)
			(end 0.12065 -0.2794)
			(stroke
				(width 0.1)
				(type default)
			)
			(layer "B.Fab")
		)
		(fp_line
			(start -0.12065 -0.3048)
			(end -0.67945 -0.3048)
			(stroke
				(width 0.1)
				(type default)
			)
			(layer "B.Fab")
		)
		(fp_line
			(start -0.67945 -0.3048)
			(end -0.67945 0.3048)
			(stroke
				(width 0.1)
				(type default)
			)
			(layer "B.Fab")
		)
		(fp_line
			(start 0.12065 -0.2794)
			(end -0.12065 -0.2794)
			(stroke
				(width 0.1)
				(type default)
			)
			(layer "B.Fab")
		)
		(fp_line
			(start -0.12065 -0.2794)
			(end -0.12065 -0.3048)
			(stroke
				(width 0.1)
				(type default)
			)
			(layer "B.Fab")
		)
		(fp_line
			(start 0.12065 0.2794)
			(end 0.12065 0.3048)
			(stroke
				(width 0.1)
				(type default)
			)
			(layer "B.Fab")
		)
		(fp_line
			(start -0.120396 0.2794)
			(end 0.12065 0.2794)
			(stroke
				(width 0.1)
				(type default)
			)
			(layer "B.Fab")
		)
		(fp_line
			(start 0.67945 0.3048)
			(end 0.67945 -0.305054)
			(stroke
				(width 0.1)
				(type default)
			)
			(layer "B.Fab")
		)
		(fp_line
			(start 0.12065 0.3048)
			(end 0.67945 0.3048)
			(stroke
				(width 0.1)
				(type default)
			)
			(layer "B.Fab")
		)
		(fp_line
			(start -0.120396 0.3048)
			(end -0.120396 0.2794)
			(stroke
				(width 0.1)
				(type default)
			)
			(layer "B.Fab")
		)
		(fp_line
			(start -0.67945 0.3048)
			(end -0.120396 0.3048)
			(stroke
				(width 0.1)
				(type default)
			)
			(layer "B.Fab")
		)
		(pad "1" smd circle
			(at 0.40005 0 270)
			(size 0 0)
			(layers "B.Cu" "B.Mask" "B.Paste")
			(net "PVDD18_S5_P0")
		)
		(pad "2" smd circle
			(at -0.40005 0 270)
			(size 0 0)
			(layers "B.Cu" "B.Mask" "B.Paste")
			(net "GND")
		)
	)
	(footprint ""
		(layer "B.Cu")
		(at 153.228294 -202.93076 90)
		(property "Reference" "R526"
			(at 0 0 90)
			(layer "B.SilkS")
			(hide yes)
			(effects
				(font
					(size 1.27 1.27)
				)
				(justify mirror)
			)
		)
		(property "Value" ""
			(at 0 0 90)
			(layer "B.Fab")
			(effects
				(font
					(size 1.27 1.27)
				)
				(justify mirror)
			)
		)
		(duplicate_pad_numbers_are_jumpers no)
		(fp_line
			(start 0.7874 -0.4064)
			(end -0.7874 -0.4064)
			(stroke
				(width 0.1524)
				(type default)
			)
			(layer "B.SilkS")
		)
		(fp_line
			(start -0.7874 -0.4064)
			(end -0.7874 0.4064)
			(stroke
				(width 0.1524)
				(type default)
			)
			(layer "B.SilkS")
		)
		(fp_line
			(start 0.7874 0.4064)
			(end 0.7874 -0.4064)
			(stroke
				(width 0.1524)
				(type default)
			)
			(layer "B.SilkS")
		)
		(fp_line
			(start -0.7874 0.4064)
			(end 0.7874 0.4064)
			(stroke
				(width 0.1524)
				(type default)
			)
			(layer "B.SilkS")
		)
		(fp_line
			(start 0.67945 -0.305054)
			(end 0.12065 -0.305054)
			(stroke
				(width 0.1)
				(type default)
			)
			(layer "B.Fab")
		)
		(fp_line
			(start 0.12065 -0.305054)
			(end 0.12065 -0.2794)
			(stroke
				(width 0.1)
				(type default)
			)
			(layer "B.Fab")
		)
		(fp_line
			(start -0.12065 -0.3048)
			(end -0.67945 -0.3048)
			(stroke
				(width 0.1)
				(type default)
			)
			(layer "B.Fab")
		)
		(fp_line
			(start -0.67945 -0.3048)
			(end -0.67945 0.3048)
			(stroke
				(width 0.1)
				(type default)
			)
			(layer "B.Fab")
		)
		(fp_line
			(start 0.12065 -0.2794)
			(end -0.12065 -0.2794)
			(stroke
				(width 0.1)
				(type default)
			)
			(layer "B.Fab")
		)
		(fp_line
			(start -0.12065 -0.2794)
			(end -0.12065 -0.3048)
			(stroke
				(width 0.1)
				(type default)
			)
			(layer "B.Fab")
		)
		(fp_line
			(start 0.12065 0.2794)
			(end 0.12065 0.3048)
			(stroke
				(width 0.1)
				(type default)
			)
			(layer "B.Fab")
		)
		(fp_line
			(start -0.120396 0.2794)
			(end 0.12065 0.2794)
			(stroke
				(width 0.1)
				(type default)
			)
			(layer "B.Fab")
		)
		(fp_line
			(start 0.67945 0.3048)
			(end 0.67945 -0.305054)
			(stroke
				(width 0.1)
				(type default)
			)
			(layer "B.Fab")
		)
		(fp_line
			(start 0.12065 0.3048)
			(end 0.67945 0.3048)
			(stroke
				(width 0.1)
				(type default)
			)
			(layer "B.Fab")
		)
		(fp_line
			(start -0.120396 0.3048)
			(end -0.120396 0.2794)
			(stroke
				(width 0.1)
				(type default)
			)
			(layer "B.Fab")
		)
		(fp_line
			(start -0.67945 0.3048)
			(end -0.120396 0.3048)
			(stroke
				(width 0.1)
				(type default)
			)
			(layer "B.Fab")
		)
		(pad "1" smd circle
			(at 0.40005 0 270)
			(size 0 0)
			(layers "B.Cu" "B.Mask" "B.Paste")
			(net "PVDD18_S5_P1")
		)
		(pad "2" smd circle
			(at -0.40005 0 270)
			(size 0 0)
			(layers "B.Cu" "B.Mask" "B.Paste")
			(net "JTAG_CPU1_TCK")
		)
	)
)
